# S9S_MB_2U (Grand Teton) — schematic netlist excerpt (pin names and nets, part order shuffled) for the footprints in the layout excerpt that follows; sources: Cadence DE-HDL packaged netlist, KiCad conversion of 03242023_DA0F0TMBIJ0_F0T_Motherboard_J_brd_V01_OCP.brd

C1232  Q_CAP  22UF 16V 20% X6S  pkg C0805  page 153 : A = P12V_OCP_SFF ; B = GND
PC1256  Q_CAP  22UF 4V 20% X6S  pkg C0805  page 281 : A = PVPP_HBM_CPU0 ; B = GND
R261  Q_RES  240 1% EMPTY  pkg 0402LF  page 119 : A = PVNN_TERM_CPU1 ; B = PU_CPU1_TXT_AGENT

(kicad_pcb
	(version 20260206)
	(generator "pcbnew")
	(generator_version "10.0")
	(general
		(thickness 1.6)
		(legacy_teardrops no)
	)
	(paper "A4")
	(title_block
		(title "03242023_DA0F0TMBIJ0_F0T_Motherboard_J_brd_V01_OCP.brd")
		(comment 1 "Grand Teton / footprints 5132-5134 of 6105")
	)
	(layers
		(0 "F.Cu" signal "TOP")
		(4 "In1.Cu" signal "GND")
		(6 "In2.Cu" signal "IN1")
		(8 "In3.Cu" signal "GND1")
		(10 "In4.Cu" signal "IN2")
		(12 "In5.Cu" signal "GND2")
		(14 "In6.Cu" signal "IN3")
		(16 "In7.Cu" signal "GND3")
		(18 "In8.Cu" signal "VCC")
		(20 "In9.Cu" signal "VCC1")
		(22 "In10.Cu" signal "GND4")
		(24 "In11.Cu" signal "IN4")
		(26 "In12.Cu" signal "GND5")
		(28 "In13.Cu" signal "IN5")
		(30 "In14.Cu" signal "GND6")
		(32 "In15.Cu" signal "IN6")
		(34 "In16.Cu" signal "GND7")
		(2 "B.Cu" signal "BOTTOM")
		(9 "F.Adhes" user "F.Adhesive")
		(11 "B.Adhes" user "B.Adhesive")
		(13 "F.Paste" user "Package Geometry/Pastemask Top")
		(15 "B.Paste" user "Package Geometry/Pastemask Bottom")
		(5 "F.SilkS" user "Ref Des/Silkscreen Top")
		(7 "B.SilkS" user "Ref Des/Silkscreen Bottom")
		(1 "F.Mask" user "Board Geometry/Soldermask Top")
		(3 "B.Mask" user "Board Geometry/Soldermask Bottom")
		(17 "Dwgs.User" user "User.Drawings")
		(19 "Cmts.User" user "User.Comments")
		(21 "Eco1.User" user "User.Eco1")
		(23 "Eco2.User" user "User.Eco2")
		(25 "Edge.Cuts" user "Board Geometry/Outline")
		(27 "Margin" user)
		(31 "F.CrtYd" user "Package Geometry/Place Bound Top")
		(29 "B.CrtYd" user "Package Geometry/Place Bound Bottom")
		(35 "F.Fab" user "Ref Des/Assembly Top")
		(33 "B.Fab" user "Ref Des/Assembly Bottom")
	)
	(footprint ""
		(layer "B.Cu")
		(at 85.457284 -190.705232 -90)
		(property "Reference" "R261"
			(at 0 0 90)
			(layer "B.SilkS")
			(hide yes)
			(effects
				(font
					(size 1.27 1.27)
				)
				(justify mirror)
			)
		)
		(property "Value" ""
			(at 0 0 90)
			(layer "B.Fab")
			(effects
				(font
					(size 1.27 1.27)
				)
				(justify mirror)
			)
		)
		(duplicate_pad_numbers_are_jumpers no)
		(fp_line
			(start -0.7874 0.4064)
			(end 0.7874 0.4064)
			(stroke
				(width 0.1524)
				(type default)
			)
			(layer "B.SilkS")
		)
		(fp_line
			(start 0.7874 0.4064)
			(end 0.7874 -0.4064)
			(stroke
				(width 0.1524)
				(type default)
			)
			(layer "B.SilkS")
		)
		(fp_line
			(start -0.7874 -0.4064)
			(end -0.7874 0.4064)
			(stroke
				(width 0.1524)
				(type default)
			)
			(layer "B.SilkS")
		)
		(fp_line
			(start 0.7874 -0.4064)
			(end -0.7874 -0.4064)
			(stroke
				(width 0.1524)
				(type default)
			)
			(layer "B.SilkS")
		)
		(fp_line
			(start -0.67945 0.3048)
			(end -0.120396 0.3048)
			(stroke
				(width 0.1)
				(type default)
			)
			(layer "B.Fab")
		)
		(fp_line
			(start -0.120396 0.3048)
			(end -0.120396 0.2794)
			(stroke
				(width 0.1)
				(type default)
			)
			(layer "B.Fab")
		)
		(fp_line
			(start 0.12065 0.3048)
			(end 0.67945 0.3048)
			(stroke
				(width 0.1)
				(type default)
			)
			(layer "B.Fab")
		)
		(fp_line
			(start 0.67945 0.3048)
			(end 0.67945 -0.305054)
			(stroke
				(width 0.1)
				(type default)
			)
			(layer "B.Fab")
		)
		(fp_line
			(start -0.120396 0.2794)
			(end 0.12065 0.2794)
			(stroke
				(width 0.1)
				(type default)
			)
			(layer "B.Fab")
		)
		(fp_line
			(start 0.12065 0.2794)
			(end 0.12065 0.3048)
			(stroke
				(width 0.1)
				(type default)
			)
			(layer "B.Fab")
		)
		(fp_line
			(start -0.12065 -0.2794)
			(end -0.12065 -0.3048)
			(stroke
				(width 0.1)
				(type default)
			)
			(layer "B.Fab")
		)
		(fp_line
			(start 0.12065 -0.2794)
			(end -0.12065 -0.2794)
			(stroke
				(width 0.1)
				(type default)
			)
			(layer "B.Fab")
		)
		(fp_line
			(start -0.67945 -0.3048)
			(end -0.67945 0.3048)
			(stroke
				(width 0.1)
				(type default)
			)
			(layer "B.Fab")
		)
		(fp_line
			(start -0.12065 -0.3048)
			(end -0.67945 -0.3048)
			(stroke
				(width 0.1)
				(type default)
			)
			(layer "B.Fab")
		)
		(fp_line
			(start 0.12065 -0.305054)
			(end 0.12065 -0.2794)
			(stroke
				(width 0.1)
				(type default)
			)
			(layer "B.Fab")
		)
		(fp_line
			(start 0.67945 -0.305054)
			(end 0.12065 -0.305054)
			(stroke
				(width 0.1)
				(type default)
			)
			(layer "B.Fab")
		)
		(pad "1" smd circle
			(at 0.40005 0 90)
			(size 0 0)
			(layers "B.Cu" "B.Mask" "B.Paste")
			(net "PVNN_TERM_CPU1")
		)
		(pad "2" smd circle
			(at -0.40005 0 90)
			(size 0 0)
			(layers "B.Cu" "B.Mask" "B.Paste")
			(net "PU_CPU1_TXT_AGENT")
		)
	)
	(footprint ""
		(layer "B.Cu")
		(at 373.810276 -366.755426 90)
		(property "Reference" "PC1256"
			(at 0 0 90)
			(layer "B.SilkS")
			(hide yes)
			(effects
				(font
					(size 1.27 1.27)
				)
				(justify mirror)
			)
		)
		(property "Value" ""
			(at 0 0 90)
			(layer "B.Fab")
			(effects
				(font
					(size 1.27 1.27)
				)
				(justify mirror)
			)
		)
		(duplicate_pad_numbers_are_jumpers no)
		(fp_line
			(start 1.524 -0.762)
			(end -1.524 -0.762)
			(stroke
				(width 0.1524)
				(type default)
			)
			(layer "B.SilkS")
		)
		(fp_line
			(start -1.524 -0.762)
			(end -1.524 0.762)
			(stroke
				(width 0.1524)
				(type default)
			)
			(layer "B.SilkS")
		)
		(fp_line
			(start 1.524 0.762)
			(end 1.524 -0.762)
			(stroke
				(width 0.1524)
				(type default)
			)
			(layer "B.SilkS")
		)
		(fp_line
			(start -1.524 0.762)
			(end 1.524 0.762)
			(stroke
				(width 0.1524)
				(type default)
			)
			(layer "B.SilkS")
		)
		(fp_line
			(start 1.1049 -0.724916)
			(end 1.1049 0.724916)
			(stroke
				(width 0.1)
				(type default)
			)
			(layer "B.Fab")
		)
		(fp_line
			(start -1.1049 -0.724916)
			(end 1.1049 -0.724916)
			(stroke
				(width 0.1)
				(type default)
			)
			(layer "B.Fab")
		)
		(fp_line
			(start 1.1049 0.724916)
			(end -1.1049 0.724916)
			(stroke
				(width 0.1)
				(type default)
			)
			(layer "B.Fab")
		)
		(fp_line
			(start -1.1049 0.724916)
			(end -1.1049 -0.724916)
			(stroke
				(width 0.1)
				(type default)
			)
			(layer "B.Fab")
		)
		(pad "1" smd rect
			(at 0.889 0 90)
			(size 1.016 1.27)
			(layers "B.Cu" "B.Mask" "B.Paste")
			(net "PVPP_HBM_CPU0")
		)
		(pad "2" smd rect
			(at -0.889 0 90)
			(size 1.016 1.27)
			(layers "B.Cu" "B.Mask" "B.Paste")
			(net "GND")
		)
	)
	(footprint ""
		(layer "B.Cu")
		(at 440.137804 -18.27022)
		(property "Reference" "C1232"
			(at 0 0 0)
			(layer "B.SilkS")
			(hide yes)
			(effects
				(font
					(size 1.27 1.27)
				)
				(justify mirror)
			)
		)
		(property "Value" ""
			(at 0 0 0)
			(layer "B.Fab")
			(effects
				(font
					(size 1.27 1.27)
				)
				(justify mirror)
			)
		)
		(duplicate_pad_numbers_are_jumpers no)
		(fp_line
			(start -1.524 -0.762)
			(end -1.524 0.762)
			(stroke
				(width 0.1524)
				(type default)
			)
			(layer "B.SilkS")
		)
		(fp_line
			(start -1.524 0.762)
			(end 1.524 0.762)
			(stroke
				(width 0.1524)
				(type default)
			)
			(layer "B.SilkS")
		)
		(fp_line
			(start 1.524 -0.762)
			(end -1.524 -0.762)
			(stroke
				(width 0.1524)
				(type default)
			)
			(layer "B.SilkS")
		)
		(fp_line
			(start 1.524 0.762)
			(end 1.524 -0.762)
			(stroke
				(width 0.1524)
				(type default)
			)
			(layer "B.SilkS")
		)
		(fp_line
			(start -1.1049 -0.724916)
			(end 1.1049 -0.724916)
			(stroke
				(width 0.1)
				(type default)
			)
			(layer "B.Fab")
		)
		(fp_line
			(start -1.1049 0.724916)
			(end -1.1049 -0.724916)
			(stroke
				(width 0.1)
				(type default)
			)
			(layer "B.Fab")
		)
		(fp_line
			(start 1.1049 -0.724916)
			(end 1.1049 0.724916)
			(stroke
				(width 0.1)
				(type default)
			)
			(layer "B.Fab")
		)
		(fp_line
			(start 1.1049 0.724916)
			(end -1.1049 0.724916)
			(stroke
				(width 0.1)
				(type default)
			)
			(layer "B.Fab")
		)
		(pad "1" smd rect
			(at 0.889 0)
			(size 1.016 1.27)
			(layers "B.Cu" "B.Mask" "B.Paste")
			(net "P12V_OCP_SFF")
		)
		(pad "2" smd rect
			(at -0.889 0)
			(size 1.016 1.27)
			(layers "B.Cu" "B.Mask" "B.Paste")
			(net "GND")
		)
	)
)
